# TIMECARD (Time Appliance Project (Time Card)) — schematic netlist excerpt (pin names and nets, part order shuffled) for the footprints in the layout excerpt that follows; sources: Cadence DE-HDL packaged netlist, KiCad conversion of R4006-B0001-02_R01.brd

C19  CAPACITOR  0.1UF 10%  pkg SMC_0402R_H022  page 9 : \1\ = C_PCIEREFCLKP ; \2\ = PCIE_REFCLKP
C204  CAPACITOR  0.1UF 10V 10%  pkg SMC_0402R_H022  page 14 : \1\ = XP2R5V_FPGA ; \2\ = SG

(kicad_pcb
	(version 20260206)
	(generator "pcbnew")
	(generator_version "10.0")
	(general
		(thickness 1.6)
		(legacy_teardrops no)
	)
	(paper "A4")
	(title_block
		(title "timecard-production-celestica-r4006 — R4006-B0001-02_R01.brd")
		(comment 1 "Time Appliance Project (Time Card) / footprints 773-774 of 1113")
	)
	(layers
		(0 "F.Cu" signal "TOP")
		(4 "In1.Cu" signal "L02_GND1")
		(6 "In2.Cu" signal "L03_SIG1")
		(8 "In3.Cu" signal "L04_GND2")
		(10 "In4.Cu" signal "L05_VCC1")
		(12 "In5.Cu" signal "L06_VCC2")
		(14 "In6.Cu" signal "L07_GND3")
		(16 "In7.Cu" signal "L08_SIG2")
		(18 "In8.Cu" signal "L09_GND4")
		(2 "B.Cu" signal "BOTTOM")
		(9 "F.Adhes" user "F.Adhesive")
		(11 "B.Adhes" user "B.Adhesive")
		(13 "F.Paste" user "Package Geometry/Pastemask Top")
		(15 "B.Paste" user "Package Geometry/Pastemask Bottom")
		(5 "F.SilkS" user "Ref Des/Silkscreen Top")
		(7 "B.SilkS" user "Ref Des/Silkscreen Bottom")
		(1 "F.Mask" user "Board Geometry/Soldermask Top")
		(3 "B.Mask" user "Board Geometry/Soldermask Bottom")
		(17 "Dwgs.User" user "User.Drawings")
		(19 "Cmts.User" user "User.Comments")
		(21 "Eco1.User" user "User.Eco1")
		(23 "Eco2.User" user "User.Eco2")
		(25 "Edge.Cuts" user "Board Geometry/Outline")
		(27 "Margin" user)
		(31 "F.CrtYd" user "Package Geometry/Place Bound Top")
		(29 "B.CrtYd" user "Package Geometry/Place Bound Bottom")
		(35 "F.Fab" user "Ref Des/Assembly Top")
		(33 "B.Fab" user "Ref Des/Assembly Bottom")
	)
	(footprint ""
		(layer "B.Cu")
		(at 59.51474 -15.36446 -90)
		(property "Reference" "C19"
			(at -2.41554 0.11811 270)
			(unlocked yes)
			(layer "B.SilkS")
			(effects
				(font
					(size 0.7874 0.5842)
					(thickness 0.1524)
				)
				(justify mirror)
			)
		)
		(property "Value" "VAL*"
			(at -0.0762 2.067306 270)
			(unlocked yes)
			(layer "B.Fab")
			(hide yes)
			(effects
				(font
					(size 0.7874 0.5842)
					(thickness 0.1524)
				)
				(justify mirror)
			)
		)
		(property "Tolerance" "TOL*"
			(at -0.0762 3.032506 270)
			(unlocked yes)
			(layer "Cmts.User")
			(hide yes)
			(effects
				(font
					(size 0.7874 0.5842)
					(thickness 0.1524)
				)
				(justify mirror)
			)
		)
		(property "User Part Number" "PARTNUM*"
			(at -0.1016 4.023106 270)
			(unlocked yes)
			(layer "Cmts.User")
			(hide yes)
			(effects
				(font
					(size 0.7874 0.5842)
					(thickness 0.1524)
				)
				(justify mirror)
			)
		)
		(property "Device Type" "CAPACITOR-G105-0B104-CK,0.1UF,A"
			(at -0.0508 1.127506 270)
			(unlocked yes)
			(layer "B.Fab")
			(hide yes)
			(effects
				(font
					(size 0.7874 0.5842)
					(thickness 0.1524)
				)
				(justify mirror)
			)
		)
		(duplicate_pad_numbers_are_jumpers no)
		(fp_line
			(start -1.143 0.5588)
			(end -1.143 -0.5588)
			(stroke
				(width 0.1)
				(type default)
			)
			(layer "B.SilkS")
		)
		(fp_line
			(start 1.143 0.5588)
			(end -1.143 0.5588)
			(stroke
				(width 0.1)
				(type default)
			)
			(layer "B.SilkS")
		)
		(fp_line
			(start -1.143 -0.5588)
			(end 1.143 -0.5588)
			(stroke
				(width 0.1)
				(type default)
			)
			(layer "B.SilkS")
		)
		(fp_line
			(start 1.143 -0.5588)
			(end 1.143 0.5588)
			(stroke
				(width 0.1)
				(type default)
			)
			(layer "B.SilkS")
		)
		(fp_rect
			(start 1.143 0.5588)
			(end -1.143 -0.5588)
			(stroke
				(width 0)
				(type default)
			)
			(fill no)
			(layer "B.CrtYd")
		)
		(fp_line
			(start -0.508 0.3048)
			(end -0.508 -0.3048)
			(stroke
				(width 0.1)
				(type default)
			)
			(layer "B.Fab")
		)
		(fp_line
			(start 0.508 0.3048)
			(end -0.508 0.3048)
			(stroke
				(width 0.1)
				(type default)
			)
			(layer "B.Fab")
		)
		(fp_line
			(start -0.508 -0.3048)
			(end 0.508 -0.3048)
			(stroke
				(width 0.1)
				(type default)
			)
			(layer "B.Fab")
		)
		(fp_line
			(start 0.508 -0.3048)
			(end 0.508 0.3048)
			(stroke
				(width 0.1)
				(type default)
			)
			(layer "B.Fab")
		)
		(pad "1" smd rect
			(at 0.5334 0 90)
			(size 0.7112 0.6096)
			(layers "B.Cu" "B.Mask" "B.Paste")
			(net "C_PCIEREFCLKP")
		)
		(pad "2" smd rect
			(at -0.5334 0 90)
			(size 0.7112 0.6096)
			(layers "B.Cu" "B.Mask" "B.Paste")
			(net "PCIE_REFCLKP")
		)
		(zone
			(layer "B.Cu")
			(hatch none 0.5)
			(connect_pads
				(clearance 0)
			)
			(min_thickness 0.25)
			(keepout
				(tracks allowed)
				(vias not_allowed)
				(pads allowed)
				(copperpour not_allowed)
				(footprints allowed)
			)
			(placement
				(enabled no)
				(sheetname "")
			)
			(fill
				(thermal_gap 0.5)
				(thermal_bridge_width 0.5)
				(island_removal_mode 0)
			)
			(polygon
				(pts
					(xy 59.20994 -15.28826) (xy 59.81954 -15.28826) (xy 59.81954 -15.44066) (xy 59.20994 -15.44066)
				)
			)
		)
	)
	(footprint ""
		(layer "B.Cu")
		(at 105.347008 -38.823138)
		(property "Reference" "C204"
			(at -41.656508 1.377188 0)
			(unlocked yes)
			(layer "B.SilkS")
			(effects
				(font
					(size 0.635 0.4064)
					(thickness 0.1524)
				)
				(justify mirror)
			)
		)
		(property "Value" "VAL*"
			(at 0 3.718306 0)
			(unlocked yes)
			(layer "B.Fab")
			(hide yes)
			(effects
				(font
					(size 0.7874 0.5842)
					(thickness 0.127)
				)
				(justify mirror)
			)
		)
		(property "Device Type" "CAPACITOR-G105-0B104-CK,0.1UF,A"
			(at 0 1.432306 0)
			(unlocked yes)
			(layer "B.Fab")
			(hide yes)
			(effects
				(font
					(size 0.7874 0.5842)
					(thickness 0.127)
				)
				(justify mirror)
			)
		)
		(property "User Part Number" "PARTNUM*"
			(at 0 2.575306 0)
			(unlocked yes)
			(layer "Cmts.User")
			(hide yes)
			(effects
				(font
					(size 0.7874 0.5842)
					(thickness 0.127)
				)
				(justify mirror)
			)
		)
		(property "Tolerance" "TOL*"
			(at 0 4.861306 0)
			(unlocked yes)
			(layer "Cmts.User")
			(hide yes)
			(effects
				(font
					(size 0.7874 0.5842)
					(thickness 0.127)
				)
				(justify mirror)
			)
		)
		(duplicate_pad_numbers_are_jumpers no)
		(fp_line
			(start -0.970026 -0.4699)
			(end -0.970026 0.4699)
			(stroke
				(width 0.1)
				(type default)
			)
			(layer "B.SilkS")
		)
		(fp_line
			(start -0.970026 0.4699)
			(end 0.970026 0.4699)
			(stroke
				(width 0.1)
				(type default)
			)
			(layer "B.SilkS")
		)
		(fp_line
			(start 0.970026 -0.4699)
			(end -0.970026 -0.4699)
			(stroke
				(width 0.1)
				(type default)
			)
			(layer "B.SilkS")
		)
		(fp_line
			(start 0.970026 0.4699)
			(end 0.970026 -0.4699)
			(stroke
				(width 0.1)
				(type default)
			)
			(layer "B.SilkS")
		)
		(fp_poly
			(pts
				(xy 0.970026 0.4699) (xy -0.970026 0.4699) (xy -0.970026 -0.4699) (xy 0.970026 -0.4699)
			)
			(stroke
				(width 0)
				(type default)
			)
			(fill no)
			(layer "B.CrtYd")
		)
		(fp_line
			(start -0.508 -0.3048)
			(end -0.508 0.3048)
			(stroke
				(width 0.1)
				(type default)
			)
			(layer "B.Fab")
		)
		(fp_line
			(start -0.508 0.3048)
			(end 0.508 0.3048)
			(stroke
				(width 0.1)
				(type default)
			)
			(layer "B.Fab")
		)
		(fp_line
			(start 0.508 -0.3048)
			(end -0.508 -0.3048)
			(stroke
				(width 0.1)
				(type default)
			)
			(layer "B.Fab")
		)
		(fp_line
			(start 0.508 0.3048)
			(end 0.508 -0.3048)
			(stroke
				(width 0.1)
				(type default)
			)
			(layer "B.Fab")
		)
		(pad "1" smd circle
			(at 0.500126 0 180)
			(size 0.635 0.635)
			(layers "B.Cu" "B.Mask" "B.Paste")
			(net "XP2R5V_FPGA")
		)
		(pad "2" smd circle
			(at -0.500126 0 180)
			(size 0.635 0.635)
			(layers "B.Cu" "B.Mask" "B.Paste")
			(net "SG")
		)
	)
)
